# S9S_MB_2U (Grand Teton) — schematic netlist excerpt (pin names and nets, part order shuffled) for the footprints in the layout excerpt that follows; sources: Cadence DE-HDL packaged netlist, KiCad conversion of 03242023_DA0F0TMBIJ0_F0T_Motherboard_J_brd_V01_OCP.brd

PC231_P0_7  Q_CAP  3300PF 50V 10% X7R  pkg 0402  page 270 : A = SW_P12V_PVCCIN_CPU0_FLT ; B = GND
C1005  Q_CAP  10UF 6.3V 20% X6S  pkg C0402  page 74 : A = PVCCIN_CPU0 ; B = GND

(kicad_pcb
	(version 20260206)
	(generator "pcbnew")
	(generator_version "10.0")
	(general
		(thickness 1.6)
		(legacy_teardrops no)
	)
	(paper "A4")
	(title_block
		(title "03242023_DA0F0TMBIJ0_F0T_Motherboard_J_brd_V01_OCP.brd")
		(comment 1 "Grand Teton / footprints 3036-3037 of 6105")
	)
	(layers
		(0 "F.Cu" signal "TOP")
		(4 "In1.Cu" signal "GND")
		(6 "In2.Cu" signal "IN1")
		(8 "In3.Cu" signal "GND1")
		(10 "In4.Cu" signal "IN2")
		(12 "In5.Cu" signal "GND2")
		(14 "In6.Cu" signal "IN3")
		(16 "In7.Cu" signal "GND3")
		(18 "In8.Cu" signal "VCC")
		(20 "In9.Cu" signal "VCC1")
		(22 "In10.Cu" signal "GND4")
		(24 "In11.Cu" signal "IN4")
		(26 "In12.Cu" signal "GND5")
		(28 "In13.Cu" signal "IN5")
		(30 "In14.Cu" signal "GND6")
		(32 "In15.Cu" signal "IN6")
		(34 "In16.Cu" signal "GND7")
		(2 "B.Cu" signal "BOTTOM")
		(9 "F.Adhes" user "F.Adhesive")
		(11 "B.Adhes" user "B.Adhesive")
		(13 "F.Paste" user "Package Geometry/Pastemask Top")
		(15 "B.Paste" user "Package Geometry/Pastemask Bottom")
		(5 "F.SilkS" user "Ref Des/Silkscreen Top")
		(7 "B.SilkS" user "Ref Des/Silkscreen Bottom")
		(1 "F.Mask" user "Board Geometry/Soldermask Top")
		(3 "B.Mask" user "Board Geometry/Soldermask Bottom")
		(17 "Dwgs.User" user "User.Drawings")
		(19 "Cmts.User" user "User.Comments")
		(21 "Eco1.User" user "User.Eco1")
		(23 "Eco2.User" user "User.Eco2")
		(25 "Edge.Cuts" user "Board Geometry/Outline")
		(27 "Margin" user)
		(31 "F.CrtYd" user "Package Geometry/Place Bound Top")
		(29 "B.CrtYd" user "Package Geometry/Place Bound Bottom")
		(35 "F.Fab" user "Ref Des/Assembly Top")
		(33 "B.Fab" user "Ref Des/Assembly Bottom")
	)
	(footprint ""
		(layer "F.Cu")
		(at 366.48263 -245.634002 -90)
		(property "Reference" "C1005"
			(at 0 0 270)
			(layer "F.SilkS")
			(hide yes)
			(effects
				(font
					(size 1.27 1.27)
				)
			)
		)
		(property "Value" ""
			(at 0 0 270)
			(layer "F.Fab")
			(effects
				(font
					(size 1.27 1.27)
				)
			)
		)
		(duplicate_pad_numbers_are_jumpers no)
		(fp_line
			(start -0.7874 0.4064)
			(end -0.7874 -0.4064)
			(stroke
				(width 0.1524)
				(type default)
			)
			(layer "F.SilkS")
		)
		(fp_line
			(start 0.7874 0.4064)
			(end -0.7874 0.4064)
			(stroke
				(width 0.1524)
				(type default)
			)
			(layer "F.SilkS")
		)
		(fp_line
			(start -0.7874 -0.4064)
			(end 0.7874 -0.4064)
			(stroke
				(width 0.1524)
				(type default)
			)
			(layer "F.SilkS")
		)
		(fp_line
			(start 0.7874 -0.4064)
			(end 0.7874 0.4064)
			(stroke
				(width 0.1524)
				(type default)
			)
			(layer "F.SilkS")
		)
		(fp_line
			(start -0.67945 0.3048)
			(end -0.67945 -0.305054)
			(stroke
				(width 0.1)
				(type default)
			)
			(layer "F.Fab")
		)
		(fp_line
			(start -0.12065 0.3048)
			(end -0.67945 0.3048)
			(stroke
				(width 0.1)
				(type default)
			)
			(layer "F.Fab")
		)
		(fp_line
			(start 0.120396 0.3048)
			(end 0.120396 0.2794)
			(stroke
				(width 0.1)
				(type default)
			)
			(layer "F.Fab")
		)
		(fp_line
			(start 0.67945 0.3048)
			(end 0.120396 0.3048)
			(stroke
				(width 0.1)
				(type default)
			)
			(layer "F.Fab")
		)
		(fp_line
			(start -0.12065 0.2794)
			(end -0.12065 0.3048)
			(stroke
				(width 0.1)
				(type default)
			)
			(layer "F.Fab")
		)
		(fp_line
			(start 0.120396 0.2794)
			(end -0.12065 0.2794)
			(stroke
				(width 0.1)
				(type default)
			)
			(layer "F.Fab")
		)
		(fp_line
			(start -0.12065 -0.2794)
			(end 0.12065 -0.2794)
			(stroke
				(width 0.1)
				(type default)
			)
			(layer "F.Fab")
		)
		(fp_line
			(start 0.12065 -0.2794)
			(end 0.12065 -0.3048)
			(stroke
				(width 0.1)
				(type default)
			)
			(layer "F.Fab")
		)
		(fp_line
			(start 0.12065 -0.3048)
			(end 0.67945 -0.3048)
			(stroke
				(width 0.1)
				(type default)
			)
			(layer "F.Fab")
		)
		(fp_line
			(start 0.67945 -0.3048)
			(end 0.67945 0.3048)
			(stroke
				(width 0.1)
				(type default)
			)
			(layer "F.Fab")
		)
		(fp_line
			(start -0.67945 -0.305054)
			(end -0.12065 -0.305054)
			(stroke
				(width 0.1)
				(type default)
			)
			(layer "F.Fab")
		)
		(fp_line
			(start -0.12065 -0.305054)
			(end -0.12065 -0.2794)
			(stroke
				(width 0.1)
				(type default)
			)
			(layer "F.Fab")
		)
		(pad "1" smd circle
			(at -0.40005 0 270)
			(size 0 0)
			(layers "F.Cu" "F.Mask" "F.Paste")
			(net "PVCCIN_CPU0")
		)
		(pad "2" smd circle
			(at 0.40005 0 270)
			(size 0 0)
			(layers "F.Cu" "F.Mask" "F.Paste")
			(net "GND")
		)
	)
	(footprint ""
		(layer "F.Cu")
		(at 333.335884 -343.496138 -90)
		(property "Reference" "PC231_P0_7"
			(at 0 0 270)
			(layer "F.SilkS")
			(hide yes)
			(effects
				(font
					(size 1.27 1.27)
				)
			)
		)
		(property "Value" ""
			(at 0 0 270)
			(layer "F.Fab")
			(effects
				(font
					(size 1.27 1.27)
				)
			)
		)
		(duplicate_pad_numbers_are_jumpers no)
		(fp_line
			(start -0.7874 0.4064)
			(end -0.7874 -0.4064)
			(stroke
				(width 0.1524)
				(type default)
			)
			(layer "F.SilkS")
		)
		(fp_line
			(start 0.7874 0.4064)
			(end -0.7874 0.4064)
			(stroke
				(width 0.1524)
				(type default)
			)
			(layer "F.SilkS")
		)
		(fp_line
			(start -0.7874 -0.4064)
			(end 0.7874 -0.4064)
			(stroke
				(width 0.1524)
				(type default)
			)
			(layer "F.SilkS")
		)
		(fp_line
			(start 0.7874 -0.4064)
			(end 0.7874 0.4064)
			(stroke
				(width 0.1524)
				(type default)
			)
			(layer "F.SilkS")
		)
		(fp_line
			(start -0.67945 0.3048)
			(end -0.67945 -0.305054)
			(stroke
				(width 0.1)
				(type default)
			)
			(layer "F.Fab")
		)
		(fp_line
			(start -0.12065 0.3048)
			(end -0.67945 0.3048)
			(stroke
				(width 0.1)
				(type default)
			)
			(layer "F.Fab")
		)
		(fp_line
			(start 0.120396 0.3048)
			(end 0.120396 0.2794)
			(stroke
				(width 0.1)
				(type default)
			)
			(layer "F.Fab")
		)
		(fp_line
			(start 0.67945 0.3048)
			(end 0.120396 0.3048)
			(stroke
				(width 0.1)
				(type default)
			)
			(layer "F.Fab")
		)
		(fp_line
			(start -0.12065 0.2794)
			(end -0.12065 0.3048)
			(stroke
				(width 0.1)
				(type default)
			)
			(layer "F.Fab")
		)
		(fp_line
			(start 0.120396 0.2794)
			(end -0.12065 0.2794)
			(stroke
				(width 0.1)
				(type default)
			)
			(layer "F.Fab")
		)
		(fp_line
			(start -0.12065 -0.2794)
			(end 0.12065 -0.2794)
			(stroke
				(width 0.1)
				(type default)
			)
			(layer "F.Fab")
		)
		(fp_line
			(start 0.12065 -0.2794)
			(end 0.12065 -0.3048)
			(stroke
				(width 0.1)
				(type default)
			)
			(layer "F.Fab")
		)
		(fp_line
			(start 0.12065 -0.3048)
			(end 0.67945 -0.3048)
			(stroke
				(width 0.1)
				(type default)
			)
			(layer "F.Fab")
		)
		(fp_line
			(start 0.67945 -0.3048)
			(end 0.67945 0.3048)
			(stroke
				(width 0.1)
				(type default)
			)
			(layer "F.Fab")
		)
		(fp_line
			(start -0.67945 -0.305054)
			(end -0.12065 -0.305054)
			(stroke
				(width 0.1)
				(type default)
			)
			(layer "F.Fab")
		)
		(fp_line
			(start -0.12065 -0.305054)
			(end -0.12065 -0.2794)
			(stroke
				(width 0.1)
				(type default)
			)
			(layer "F.Fab")
		)
		(pad "1" smd circle
			(at -0.40005 0 270)
			(size 0 0)
			(layers "F.Cu" "F.Mask" "F.Paste")
			(net "SW_P12V_PVCCIN_CPU0_FLT")
		)
		(pad "2" smd circle
			(at 0.40005 0 270)
			(size 0 0)
			(layers "F.Cu" "F.Mask" "F.Paste")
			(net "GND")
		)
	)
)
